(kicad_pcb
	(version 20260206)
	(generator "pcbnew")
	(generator_version "10.0")
	(general
		(thickness 1.6)
		(legacy_teardrops no)
	)
	(paper "A4")
	(title_block
		(title "15969-1a.1015WZS0858.brd")
		(comment 1 "Tioga Pass / footprints 263-268 of 295")
	)
	(layers
		(0 "F.Cu" signal "TOP")
		(4 "In1.Cu" signal "L2GND")
		(6 "In2.Cu" signal "L3")
		(8 "In3.Cu" signal "L4")
		(10 "In4.Cu" signal "L5GND")
		(2 "B.Cu" signal "BOTTOM")
		(9 "F.Adhes" user "F.Adhesive")
		(11 "B.Adhes" user "B.Adhesive")
		(13 "F.Paste" user "Package Geometry/Pastemask Top")
		(15 "B.Paste" user "Package Geometry/Pastemask Bottom")
		(5 "F.SilkS" user "Ref Des/Silkscreen Top")
		(7 "B.SilkS" user "Ref Des/Silkscreen Bottom")
		(1 "F.Mask" user "Board Geometry/Soldermask Top")
		(3 "B.Mask" user "Board Geometry/Soldermask Bottom")
		(17 "Dwgs.User" user "User.Drawings")
		(19 "Cmts.User" user "User.Comments")
		(21 "Eco1.User" user "User.Eco1")
		(23 "Eco2.User" user "User.Eco2")
		(25 "Edge.Cuts" user "Board Geometry/Outline")
		(27 "Margin" user)
		(31 "F.CrtYd" user "Package Geometry/Place Bound Top")
		(29 "B.CrtYd" user "Package Geometry/Place Bound Bottom")
		(35 "F.Fab" user "Ref Des/Assembly Top")
		(33 "B.Fab" user "Ref Des/Assembly Bottom")
	)
	(footprint ""
		(layer "B.Cu")
		(at 109.6772 0.0508 -90)
		(property "Reference" "U1"
			(at 0 0 90)
			(layer "B.SilkS")
			(hide yes)
			(effects
				(font
					(size 1.27 1.27)
				)
				(justify mirror)
			)
		)
		(property "Value" "PCA9544APW-GP"
			(at 0 -11.8872 270)
			(unlocked yes)
			(layer "B.Fab")
			(hide yes)
			(effects
				(font
					(size 1.016 1.016)
					(thickness 0.1524)
				)
				(justify mirror)
			)
		)
		(property "Device Type" "TSOIC20H44"
			(at 0 -13.7922 270)
			(unlocked yes)
			(layer "B.Fab")
			(hide yes)
			(effects
				(font
					(size 1.016 1.016)
					(thickness 0.1524)
				)
				(justify mirror)
			)
		)
		(duplicate_pad_numbers_are_jumpers no)
		(fp_line
			(start 3.556 3.6322)
			(end 3.556 1.397)
			(stroke
				(width 0.508)
				(type default)
			)
			(layer "B.SilkS")
		)
		(fp_line
			(start -3.175 1.397)
			(end 3.556 1.397)
			(stroke
				(width 0.2032)
				(type default)
			)
			(layer "B.SilkS")
		)
		(fp_line
			(start 3.556 1.397)
			(end 3.556 1.778)
			(stroke
				(width 0.2032)
				(type default)
			)
			(layer "B.SilkS")
		)
		(fp_line
			(start 2.667 0)
			(end 3.556 0.889)
			(stroke
				(width 0.2032)
				(type default)
			)
			(layer "B.SilkS")
		)
		(fp_line
			(start 2.667 0)
			(end 3.556 -0.889)
			(stroke
				(width 0.2032)
				(type default)
			)
			(layer "B.SilkS")
		)
		(fp_line
			(start -3.175 -1.397)
			(end -3.175 1.397)
			(stroke
				(width 0.2032)
				(type default)
			)
			(layer "B.SilkS")
		)
		(fp_line
			(start 3.556 -1.397)
			(end 3.556 3.7084)
			(stroke
				(width 0.2032)
				(type default)
			)
			(layer "B.SilkS")
		)
		(fp_line
			(start 3.556 -1.397)
			(end -3.175 -1.397)
			(stroke
				(width 0.2032)
				(type default)
			)
			(layer "B.SilkS")
		)
		(fp_poly
			(pts
				(xy 3.25628 -1.8542) (xy -3.25628 -1.8542) (xy -3.25628 1.8542) (xy 3.25628 1.8542)
			)
			(stroke
				(width 0)
				(type default)
			)
			(fill yes)
			(layer "B.SilkS")
		)
		(fp_rect
			(start 3.556 3.81)
			(end -3.556 -3.81)
			(stroke
				(width 0)
				(type default)
			)
			(fill no)
			(layer "B.CrtYd")
		)
		(fp_poly
			(pts
				(xy 3.556 -3.81) (xy -3.556 -3.81) (xy -3.556 3.81) (xy 3.556 3.81)
			)
			(stroke
				(width 0)
				(type default)
			)
			(fill no)
			(layer "B.Fab")
		)
		(pad "1" smd rect
			(at 2.92608 2.8194 90)
			(size 0.3556 1.524)
			(layers "B.Cu" "B.Mask" "B.Paste")
			(net "SMB_B_HUB_A0")
		)
		(pad "2" smd rect
			(at 2.27584 2.8194 90)
			(size 0.3556 1.524)
			(layers "B.Cu" "B.Mask" "B.Paste")
			(net "SMB_B_HUB_A1")
		)
		(pad "3" smd rect
			(at 1.6256 2.8194 90)
			(size 0.3556 1.524)
			(layers "B.Cu" "B.Mask" "B.Paste")
			(net "SMB_B_HUB_A2")
		)
		(pad "4" smd rect
			(at 0.97536 2.8194 90)
			(size 0.3556 1.524)
			(layers "B.Cu" "B.Mask" "B.Paste")
			(net "SMB_PCIE_SLOT2_ALERT_N")
		)
		(pad "5" smd rect
			(at 0.32512 2.8194 90)
			(size 0.3556 1.524)
			(layers "B.Cu" "B.Mask" "B.Paste")
			(net "SMDAT_BMC_SLOT2")
		)
		(pad "6" smd rect
			(at -0.32512 2.8194 90)
			(size 0.3556 1.524)
			(layers "B.Cu" "B.Mask" "B.Paste")
			(net "SMCLK_BMC_SLOT2")
		)
		(pad "7" smd rect
			(at -0.97536 2.8194 90)
			(size 0.3556 1.524)
			(layers "B.Cu" "B.Mask" "B.Paste")
			(net "SMB_PCIE_SLOT3_ALERT_N")
		)
		(pad "8" smd rect
			(at -1.6256 2.8194 90)
			(size 0.3556 1.524)
			(layers "B.Cu" "B.Mask" "B.Paste")
			(net "SMDAT_BMC_SLOT3")
		)
		(pad "9" smd rect
			(at -2.27584 2.8194 90)
			(size 0.3556 1.524)
			(layers "B.Cu" "B.Mask" "B.Paste")
			(net "SMCLK_BMC_SLOT3")
		)
		(pad "10" smd rect
			(at -2.92608 2.8194 90)
			(size 0.3556 1.524)
			(layers "B.Cu" "B.Mask" "B.Paste")
			(net "GND")
		)
		(pad "11" smd rect
			(at -2.92608 -2.8194 90)
			(size 0.3556 1.524)
			(layers "B.Cu" "B.Mask" "B.Paste")
			(net "PU_I2CMUX_INT2_N")
		)
		(pad "12" smd rect
			(at -2.27584 -2.8194 90)
			(size 0.3556 1.524)
			(layers "B.Cu" "B.Mask" "B.Paste")
			(net "PU_B_MUX_SDA2")
		)
		(pad "13" smd rect
			(at -1.6256 -2.8194 90)
			(size 0.3556 1.524)
			(layers "B.Cu" "B.Mask" "B.Paste")
			(net "PU_B_MUX_SCL2")
		)
		(pad "14" smd rect
			(at -0.97536 -2.8194 90)
			(size 0.3556 1.524)
			(layers "B.Cu" "B.Mask" "B.Paste")
			(net "SMB_BMC_DEVICE_ALERT_N")
		)
		(pad "15" smd rect
			(at -0.32512 -2.8194 90)
			(size 0.3556 1.524)
			(layers "B.Cu" "B.Mask" "B.Paste")
			(net "SMDAT_BMC_DEVICE")
		)
		(pad "16" smd rect
			(at 0.32512 -2.8194 90)
			(size 0.3556 1.524)
			(layers "B.Cu" "B.Mask" "B.Paste")
			(net "SMCLK_BMC_DEVICE")
		)
		(pad "17" smd rect
			(at 0.97536 -2.8194 90)
			(size 0.3556 1.524)
			(layers "B.Cu" "B.Mask" "B.Paste")
			(net "IRQ_OOB_MGMT_RISER_ALERT_N")
		)
		(pad "18" smd rect
			(at 1.6256 -2.8194 90)
			(size 0.3556 1.524)
			(layers "B.Cu" "B.Mask" "B.Paste")
			(net "SMCLK_BMC_R")
		)
		(pad "19" smd rect
			(at 2.27584 -2.8194 90)
			(size 0.3556 1.524)
			(layers "B.Cu" "B.Mask" "B.Paste")
			(net "SMDAT_BMC_R")
		)
		(pad "20" smd rect
			(at 2.92608 -2.8194 90)
			(size 0.3556 1.524)
			(layers "B.Cu" "B.Mask" "B.Paste")
			(net "P3V3_STBY")
		)
	)
	(footprint ""
		(layer "B.Cu")
		(at 27.051 -33.2486 -90)
		(property "Reference" "R61"
			(at 0 0 90)
			(layer "B.SilkS")
			(hide yes)
			(effects
				(font
					(size 1.27 1.27)
				)
				(justify mirror)
			)
		)
		(property "Value" "0R2F-1-GP"
			(at -0.064008 -3.993896 270)
			(unlocked yes)
			(layer "B.Fab")
			(hide yes)
			(effects
				(font
					(size 1.016 1.016)
					(thickness 0.1524)
				)
				(justify mirror)
			)
		)
		(property "Device Type" "R402H16"
			(at -0.064008 -5.517896 270)
			(unlocked yes)
			(layer "B.Fab")
			(hide yes)
			(effects
				(font
					(size 1.016 1.016)
					(thickness 0.1524)
				)
				(justify mirror)
			)
		)
		(duplicate_pad_numbers_are_jumpers no)
		(fp_line
			(start -0.508 -0.9398)
			(end 0.508 -0.9398)
			(stroke
				(width 0.1524)
				(type default)
			)
			(layer "B.SilkS")
		)
		(fp_line
			(start 0.508 -0.9398)
			(end 0.508 0.9398)
			(stroke
				(width 0.1524)
				(type default)
			)
			(layer "B.SilkS")
		)
		(fp_rect
			(start 0.508 0.9398)
			(end -0.508 -0.9398)
			(stroke
				(width 0)
				(type default)
			)
			(fill no)
			(layer "B.CrtYd")
		)
		(fp_rect
			(start 0.508 0.9398)
			(end -0.508 -0.9398)
			(stroke
				(width 0)
				(type default)
			)
			(fill no)
			(layer "B.Fab")
		)
		(pad "1" smd custom
			(at 0 -0.4445 90)
			(size 0.1397 0.1397)
			(layers "B.Cu" "B.Mask" "B.Paste")
			(net "PD_SLOT3_PRSNT1")
			(options
				(clearance outline)
				(anchor circle)
			)
			(primitives
				(gr_poly
					(pts
						(arc
							(start -0.1778 0.2794)
							(mid -0.249642 0.249642)
							(end -0.2794 0.1778)
						)
						(arc
							(start -0.2794 -0.1778)
							(mid -0.249642 -0.249642)
							(end -0.1778 -0.2794)
						)
						(arc
							(start 0.1778 -0.2794)
							(mid 0.249642 -0.249642)
							(end 0.2794 -0.1778)
						)
						(arc
							(start 0.2794 0.1778)
							(mid 0.249642 0.249642)
							(end 0.1778 0.2794)
						)
					)
					(width 0)
					(fill yes)
				)
			)
		)
		(pad "2" smd custom
			(at 0 0.4445 90)
			(size 0.1397 0.1397)
			(layers "B.Cu" "B.Mask" "B.Paste")
			(net "GND")
			(options
				(clearance outline)
				(anchor circle)
			)
			(primitives
				(gr_poly
					(pts
						(arc
							(start -0.1778 0.2794)
							(mid -0.249642 0.249642)
							(end -0.2794 0.1778)
						)
						(arc
							(start -0.2794 -0.1778)
							(mid -0.249642 -0.249642)
							(end -0.1778 -0.2794)
						)
						(arc
							(start 0.1778 -0.2794)
							(mid 0.249642 -0.249642)
							(end 0.2794 -0.1778)
						)
						(arc
							(start 0.2794 0.1778)
							(mid 0.249642 0.249642)
							(end 0.1778 0.2794)
						)
					)
					(width 0)
					(fill yes)
				)
			)
		)
	)
	(footprint ""
		(layer "B.Cu")
		(at 125.6284 -11.7094)
		(property "Reference" "R53"
			(at 0 0 0)
			(layer "B.SilkS")
			(hide yes)
			(effects
				(font
					(size 1.27 1.27)
				)
				(justify mirror)
			)
		)
		(property "Value" "10KR2F-2-GP"
			(at -0.064008 -3.993896 0)
			(unlocked yes)
			(layer "B.Fab")
			(hide yes)
			(effects
				(font
					(size 1.016 1.016)
					(thickness 0.1524)
				)
				(justify mirror)
			)
		)
		(property "Device Type" "R402H16"
			(at -0.064008 -5.517896 0)
			(unlocked yes)
			(layer "B.Fab")
			(hide yes)
			(effects
				(font
					(size 1.016 1.016)
					(thickness 0.1524)
				)
				(justify mirror)
			)
		)
		(duplicate_pad_numbers_are_jumpers no)
		(fp_line
			(start -0.508 -0.9398)
			(end 0.508 -0.9398)
			(stroke
				(width 0.1524)
				(type default)
			)
			(layer "B.SilkS")
		)
		(fp_line
			(start 0.508 -0.9398)
			(end 0.508 0.9398)
			(stroke
				(width 0.1524)
				(type default)
			)
			(layer "B.SilkS")
		)
		(fp_rect
			(start 0.508 0.9398)
			(end -0.508 -0.9398)
			(stroke
				(width 0)
				(type default)
			)
			(fill no)
			(layer "B.CrtYd")
		)
		(fp_rect
			(start 0.508 0.9398)
			(end -0.508 -0.9398)
			(stroke
				(width 0)
				(type default)
			)
			(fill no)
			(layer "B.Fab")
		)
		(pad "1" smd custom
			(at 0 -0.4445 180)
			(size 0.1397 0.1397)
			(layers "B.Cu" "B.Mask" "B.Paste")
			(net "P3V3_STBY")
			(options
				(clearance outline)
				(anchor circle)
			)
			(primitives
				(gr_poly
					(pts
						(arc
							(start -0.1778 0.2794)
							(mid -0.249642 0.249642)
							(end -0.2794 0.1778)
						)
						(arc
							(start -0.2794 -0.1778)
							(mid -0.249642 -0.249642)
							(end -0.1778 -0.2794)
						)
						(arc
							(start 0.1778 -0.2794)
							(mid 0.249642 -0.249642)
							(end 0.2794 -0.1778)
						)
						(arc
							(start 0.2794 0.1778)
							(mid 0.249642 0.249642)
							(end 0.1778 0.2794)
						)
					)
					(width 0)
					(fill yes)
				)
			)
		)
		(pad "2" smd custom
			(at 0 0.4445 180)
			(size 0.1397 0.1397)
			(layers "B.Cu" "B.Mask" "B.Paste")
			(net "SMB_P_HUB_A2")
			(options
				(clearance outline)
				(anchor circle)
			)
			(primitives
				(gr_poly
					(pts
						(arc
							(start -0.1778 0.2794)
							(mid -0.249642 0.249642)
							(end -0.2794 0.1778)
						)
						(arc
							(start -0.2794 -0.1778)
							(mid -0.249642 -0.249642)
							(end -0.1778 -0.2794)
						)
						(arc
							(start 0.1778 -0.2794)
							(mid 0.249642 -0.249642)
							(end 0.2794 -0.1778)
						)
						(arc
							(start 0.2794 0.1778)
							(mid 0.249642 0.249642)
							(end 0.1778 0.2794)
						)
					)
					(width 0)
					(fill yes)
				)
			)
		)
	)
	(footprint ""
		(layer "B.Cu")
		(at 123.444 -11.5316 180)
		(property "Reference" "R110"
			(at 0 0 0)
			(layer "B.SilkS")
			(hide yes)
			(effects
				(font
					(size 1.27 1.27)
				)
				(justify mirror)
			)
		)
		(property "Value" "10KR2F-2-GP"
			(at -0.064008 -3.993896 180)
			(unlocked yes)
			(layer "B.Fab")
			(hide yes)
			(effects
				(font
					(size 1.016 1.016)
					(thickness 0.1524)
				)
				(justify mirror)
			)
		)
		(property "Device Type" "R402H16"
			(at -0.064008 -5.517896 180)
			(unlocked yes)
			(layer "B.Fab")
			(hide yes)
			(effects
				(font
					(size 1.016 1.016)
					(thickness 0.1524)
				)
				(justify mirror)
			)
		)
		(duplicate_pad_numbers_are_jumpers no)
		(fp_line
			(start 0.508 -0.9398)
			(end 0.508 0.9398)
			(stroke
				(width 0.1524)
				(type default)
			)
			(layer "B.SilkS")
		)
		(fp_line
			(start -0.508 -0.9398)
			(end 0.508 -0.9398)
			(stroke
				(width 0.1524)
				(type default)
			)
			(layer "B.SilkS")
		)
		(fp_rect
			(start 0.508 0.9398)
			(end -0.508 -0.9398)
			(stroke
				(width 0)
				(type default)
			)
			(fill no)
			(layer "B.CrtYd")
		)
		(fp_rect
			(start 0.508 0.9398)
			(end -0.508 -0.9398)
			(stroke
				(width 0)
				(type default)
			)
			(fill no)
			(layer "B.Fab")
		)
		(pad "1" smd custom
			(at 0 -0.4445)
			(size 0.1397 0.1397)
			(layers "B.Cu" "B.Mask" "B.Paste")
			(net "SMB_P_HUB_A0")
			(options
				(clearance outline)
				(anchor circle)
			)
			(primitives
				(gr_poly
					(pts
						(arc
							(start -0.1778 0.2794)
							(mid -0.249642 0.249642)
							(end -0.2794 0.1778)
						)
						(arc
							(start -0.2794 -0.1778)
							(mid -0.249642 -0.249642)
							(end -0.1778 -0.2794)
						)
						(arc
							(start 0.1778 -0.2794)
							(mid 0.249642 -0.249642)
							(end 0.2794 -0.1778)
						)
						(arc
							(start 0.2794 0.1778)
							(mid 0.249642 0.249642)
							(end 0.1778 0.2794)
						)
					)
					(width 0)
					(fill yes)
				)
			)
		)
		(pad "2" smd custom
			(at 0 0.4445)
			(size 0.1397 0.1397)
			(layers "B.Cu" "B.Mask" "B.Paste")
			(net "GND")
			(options
				(clearance outline)
				(anchor circle)
			)
			(primitives
				(gr_poly
					(pts
						(arc
							(start -0.1778 0.2794)
							(mid -0.249642 0.249642)
							(end -0.2794 0.1778)
						)
						(arc
							(start -0.2794 -0.1778)
							(mid -0.249642 -0.249642)
							(end -0.1778 -0.2794)
						)
						(arc
							(start 0.1778 -0.2794)
							(mid 0.249642 -0.249642)
							(end 0.2794 -0.1778)
						)
						(arc
							(start 0.2794 0.1778)
							(mid 0.249642 0.249642)
							(end 0.1778 0.2794)
						)
					)
					(width 0)
					(fill yes)
				)
			)
		)
	)
	(footprint ""
		(layer "B.Cu")
		(at 125.1966 -30.6578)
		(property "Reference" "CU5"
			(at 0 0 0)
			(layer "B.SilkS")
			(hide yes)
			(effects
				(font
					(size 1.27 1.27)
				)
				(justify mirror)
			)
		)
		(property "Value" "SC1U10V2KX-4-GP"
			(at -1.1811 -2.7051 0)
			(unlocked yes)
			(layer "B.Fab")
			(hide yes)
			(effects
				(font
					(size 1.016 1.016)
					(thickness 0.1524)
				)
				(justify mirror)
			)
		)
		(property "Device Type" "C402H22"
			(at -1.1811 -4.2291 0)
			(unlocked yes)
			(layer "B.Fab")
			(hide yes)
			(effects
				(font
					(size 1.016 1.016)
					(thickness 0.1524)
				)
				(justify mirror)
			)
		)
		(duplicate_pad_numbers_are_jumpers no)
		(fp_rect
			(start 0.4318 0.9525)
			(end -0.4318 -0.9525)
			(stroke
				(width 0)
				(type default)
			)
			(fill no)
			(layer "B.CrtYd")
		)
		(fp_rect
			(start 0.4318 0.9525)
			(end -0.4318 -0.9525)
			(stroke
				(width 0)
				(type default)
			)
			(fill no)
			(layer "B.Fab")
		)
		(pad "1" smd custom
			(at 0 -0.4445 180)
			(size 0.1524 0.1524)
			(layers "B.Cu" "B.Mask" "B.Paste")
			(net "P3V3_USB_HUB")
			(options
				(clearance outline)
				(anchor circle)
			)
			(primitives
				(gr_poly
					(pts
						(arc
							(start 0.3048 0.2032)
							(mid 0.275042 0.275042)
							(end 0.2032 0.3048)
						)
						(arc
							(start -0.2032 0.3048)
							(mid -0.275042 0.275042)
							(end -0.3048 0.2032)
						)
						(arc
							(start -0.3048 -0.2032)
							(mid -0.275042 -0.275042)
							(end -0.2032 -0.3048)
						)
						(arc
							(start 0.2032 -0.3048)
							(mid 0.275042 -0.275042)
							(end 0.3048 -0.2032)
						)
					)
					(width 0)
					(fill yes)
				)
			)
		)
		(pad "2" smd custom
			(at 0 0.4445 180)
			(size 0.1524 0.1524)
			(layers "B.Cu" "B.Mask" "B.Paste")
			(net "GND")
			(options
				(clearance outline)
				(anchor circle)
			)
			(primitives
				(gr_poly
					(pts
						(arc
							(start 0.3048 0.2032)
							(mid 0.275042 0.275042)
							(end 0.2032 0.3048)
						)
						(arc
							(start -0.2032 0.3048)
							(mid -0.275042 0.275042)
							(end -0.3048 0.2032)
						)
						(arc
							(start -0.3048 -0.2032)
							(mid -0.275042 -0.275042)
							(end -0.2032 -0.3048)
						)
						(arc
							(start 0.2032 -0.3048)
							(mid 0.275042 -0.275042)
							(end 0.3048 -0.2032)
						)
					)
					(width 0)
					(fill yes)
				)
			)
		)
	)
	(footprint ""
		(layer "B.Cu")
		(at 103.886 -2.0828)
		(property "Reference" "R5"
			(at 0 0 0)
			(layer "B.SilkS")
			(hide yes)
			(effects
				(font
					(size 1.27 1.27)
				)
				(justify mirror)
			)
		)
		(property "Value" "4K7R2F-GP"
			(at -0.064008 -3.993896 0)
			(unlocked yes)
			(layer "B.Fab")
			(hide yes)
			(effects
				(font
					(size 1.016 1.016)
					(thickness 0.1524)
				)
				(justify mirror)
			)
		)
		(property "Device Type" "R402H16"
			(at -0.064008 -5.517896 0)
			(unlocked yes)
			(layer "B.Fab")
			(hide yes)
			(effects
				(font
					(size 1.016 1.016)
					(thickness 0.1524)
				)
				(justify mirror)
			)
		)
		(duplicate_pad_numbers_are_jumpers no)
		(fp_line
			(start -0.508 -0.9398)
			(end 0.508 -0.9398)
			(stroke
				(width 0.1524)
				(type default)
			)
			(layer "B.SilkS")
		)
		(fp_line
			(start 0.508 -0.9398)
			(end 0.508 0.9398)
			(stroke
				(width 0.1524)
				(type default)
			)
			(layer "B.SilkS")
		)
		(fp_rect
			(start 0.508 0.9398)
			(end -0.508 -0.9398)
			(stroke
				(width 0)
				(type default)
			)
			(fill no)
			(layer "B.CrtYd")
		)
		(fp_rect
			(start 0.508 0.9398)
			(end -0.508 -0.9398)
			(stroke
				(width 0)
				(type default)
			)
			(fill no)
			(layer "B.Fab")
		)
		(pad "1" smd custom
			(at 0 -0.4445 180)
			(size 0.1397 0.1397)
			(layers "B.Cu" "B.Mask" "B.Paste")
			(net "P3V3_STBY")
			(options
				(clearance outline)
				(anchor circle)
			)
			(primitives
				(gr_poly
					(pts
						(arc
							(start -0.1778 0.2794)
							(mid -0.249642 0.249642)
							(end -0.2794 0.1778)
						)
						(arc
							(start -0.2794 -0.1778)
							(mid -0.249642 -0.249642)
							(end -0.1778 -0.2794)
						)
						(arc
							(start 0.1778 -0.2794)
							(mid 0.249642 -0.249642)
							(end 0.2794 -0.1778)
						)
						(arc
							(start 0.2794 0.1778)
							(mid 0.249642 0.249642)
							(end 0.1778 0.2794)
						)
					)
					(width 0)
					(fill yes)
				)
			)
		)
		(pad "2" smd custom
			(at 0 0.4445 180)
			(size 0.1397 0.1397)
			(layers "B.Cu" "B.Mask" "B.Paste")
			(net "SMCLK_BMC_SLOT3")
			(options
				(clearance outline)
				(anchor circle)
			)
			(primitives
				(gr_poly
					(pts
						(arc
							(start -0.1778 0.2794)
							(mid -0.249642 0.249642)
							(end -0.2794 0.1778)
						)
						(arc
							(start -0.2794 -0.1778)
							(mid -0.249642 -0.249642)
							(end -0.1778 -0.2794)
						)
						(arc
							(start 0.1778 -0.2794)
							(mid 0.249642 -0.249642)
							(end 0.2794 -0.1778)
						)
						(arc
							(start 0.2794 0.1778)
							(mid 0.249642 0.249642)
							(end 0.1778 0.2794)
						)
					)
					(width 0)
					(fill yes)
				)
			)
		)
	)
)
